(kicad_pcb
	(version 20260206)
	(generator "pcbnew")
	(generator_version "10.0")
	(general
		(thickness 1.6)
		(legacy_teardrops no)
	)
	(paper "A4")
	(title_block
		(title "03242023_DA0F0TMBIJ0_F0T_Motherboard_J_brd_V01_OCP.brd")
		(comment 1 "Grand Teton / footprints 3541-3546 of 6105")
	)
	(layers
		(0 "F.Cu" signal "TOP")
		(4 "In1.Cu" signal "GND")
		(6 "In2.Cu" signal "IN1")
		(8 "In3.Cu" signal "GND1")
		(10 "In4.Cu" signal "IN2")
		(12 "In5.Cu" signal "GND2")
		(14 "In6.Cu" signal "IN3")
		(16 "In7.Cu" signal "GND3")
		(18 "In8.Cu" signal "VCC")
		(20 "In9.Cu" signal "VCC1")
		(22 "In10.Cu" signal "GND4")
		(24 "In11.Cu" signal "IN4")
		(26 "In12.Cu" signal "GND5")
		(28 "In13.Cu" signal "IN5")
		(30 "In14.Cu" signal "GND6")
		(32 "In15.Cu" signal "IN6")
		(34 "In16.Cu" signal "GND7")
		(2 "B.Cu" signal "BOTTOM")
		(9 "F.Adhes" user "F.Adhesive")
		(11 "B.Adhes" user "B.Adhesive")
		(13 "F.Paste" user "Package Geometry/Pastemask Top")
		(15 "B.Paste" user "Package Geometry/Pastemask Bottom")
		(5 "F.SilkS" user "Ref Des/Silkscreen Top")
		(7 "B.SilkS" user "Ref Des/Silkscreen Bottom")
		(1 "F.Mask" user "Board Geometry/Soldermask Top")
		(3 "B.Mask" user "Board Geometry/Soldermask Bottom")
		(17 "Dwgs.User" user "User.Drawings")
		(19 "Cmts.User" user "User.Comments")
		(21 "Eco1.User" user "User.Eco1")
		(23 "Eco2.User" user "User.Eco2")
		(25 "Edge.Cuts" user "Board Geometry/Outline")
		(27 "Margin" user)
		(31 "F.CrtYd" user "Package Geometry/Place Bound Top")
		(29 "B.CrtYd" user "Package Geometry/Place Bound Bottom")
		(35 "F.Fab" user "Ref Des/Assembly Top")
		(33 "B.Fab" user "Ref Des/Assembly Bottom")
	)
	(footprint ""
		(layer "F.Cu")
		(at 185.928762 -26.788872 180)
		(property "Reference" "PR4008"
			(at 0 0 180)
			(layer "F.SilkS")
			(hide yes)
			(effects
				(font
					(size 1.27 1.27)
				)
			)
		)
		(property "Value" ""
			(at 0 0 180)
			(layer "F.Fab")
			(effects
				(font
					(size 1.27 1.27)
				)
			)
		)
		(duplicate_pad_numbers_are_jumpers no)
		(fp_line
			(start 0.7874 0.4064)
			(end -0.7874 0.4064)
			(stroke
				(width 0.1524)
				(type default)
			)
			(layer "F.SilkS")
		)
		(fp_line
			(start 0.7874 -0.4064)
			(end 0.7874 0.4064)
			(stroke
				(width 0.1524)
				(type default)
			)
			(layer "F.SilkS")
		)
		(fp_line
			(start -0.7874 0.4064)
			(end -0.7874 -0.4064)
			(stroke
				(width 0.1524)
				(type default)
			)
			(layer "F.SilkS")
		)
		(fp_line
			(start -0.7874 -0.4064)
			(end 0.7874 -0.4064)
			(stroke
				(width 0.1524)
				(type default)
			)
			(layer "F.SilkS")
		)
		(fp_line
			(start 0.67945 0.3048)
			(end 0.120396 0.3048)
			(stroke
				(width 0.1)
				(type default)
			)
			(layer "F.Fab")
		)
		(fp_line
			(start 0.67945 -0.3048)
			(end 0.67945 0.3048)
			(stroke
				(width 0.1)
				(type default)
			)
			(layer "F.Fab")
		)
		(fp_line
			(start 0.12065 -0.2794)
			(end 0.12065 -0.3048)
			(stroke
				(width 0.1)
				(type default)
			)
			(layer "F.Fab")
		)
		(fp_line
			(start 0.12065 -0.3048)
			(end 0.67945 -0.3048)
			(stroke
				(width 0.1)
				(type default)
			)
			(layer "F.Fab")
		)
		(fp_line
			(start 0.120396 0.3048)
			(end 0.120396 0.2794)
			(stroke
				(width 0.1)
				(type default)
			)
			(layer "F.Fab")
		)
		(fp_line
			(start 0.120396 0.2794)
			(end -0.12065 0.2794)
			(stroke
				(width 0.1)
				(type default)
			)
			(layer "F.Fab")
		)
		(fp_line
			(start -0.12065 0.3048)
			(end -0.67945 0.3048)
			(stroke
				(width 0.1)
				(type default)
			)
			(layer "F.Fab")
		)
		(fp_line
			(start -0.12065 0.2794)
			(end -0.12065 0.3048)
			(stroke
				(width 0.1)
				(type default)
			)
			(layer "F.Fab")
		)
		(fp_line
			(start -0.12065 -0.2794)
			(end 0.12065 -0.2794)
			(stroke
				(width 0.1)
				(type default)
			)
			(layer "F.Fab")
		)
		(fp_line
			(start -0.12065 -0.305054)
			(end -0.12065 -0.2794)
			(stroke
				(width 0.1)
				(type default)
			)
			(layer "F.Fab")
		)
		(fp_line
			(start -0.67945 0.3048)
			(end -0.67945 -0.305054)
			(stroke
				(width 0.1)
				(type default)
			)
			(layer "F.Fab")
		)
		(fp_line
			(start -0.67945 -0.305054)
			(end -0.12065 -0.305054)
			(stroke
				(width 0.1)
				(type default)
			)
			(layer "F.Fab")
		)
		(pad "1" smd circle
			(at -0.40005 0 180)
			(size 0 0)
			(layers "F.Cu" "F.Mask" "F.Paste")
			(net "P12V_SCM_SENSE")
		)
		(pad "2" smd circle
			(at 0.40005 0 180)
			(size 0 0)
			(layers "F.Cu" "F.Mask" "F.Paste")
			(net "GND")
		)
	)
	(footprint ""
		(layer "F.Cu")
		(at 234.126278 -245.411498 90)
		(property "Reference" "R4080"
			(at 0 0 90)
			(layer "F.SilkS")
			(hide yes)
			(effects
				(font
					(size 1.27 1.27)
				)
			)
		)
		(property "Value" ""
			(at 0 0 90)
			(layer "F.Fab")
			(effects
				(font
					(size 1.27 1.27)
				)
			)
		)
		(duplicate_pad_numbers_are_jumpers no)
		(fp_line
			(start 0.7874 -0.4064)
			(end 0.7874 0.4064)
			(stroke
				(width 0.1524)
				(type default)
			)
			(layer "F.SilkS")
		)
		(fp_line
			(start -0.7874 -0.4064)
			(end 0.7874 -0.4064)
			(stroke
				(width 0.1524)
				(type default)
			)
			(layer "F.SilkS")
		)
		(fp_line
			(start 0.7874 0.4064)
			(end -0.7874 0.4064)
			(stroke
				(width 0.1524)
				(type default)
			)
			(layer "F.SilkS")
		)
		(fp_line
			(start -0.7874 0.4064)
			(end -0.7874 -0.4064)
			(stroke
				(width 0.1524)
				(type default)
			)
			(layer "F.SilkS")
		)
		(fp_line
			(start -0.12065 -0.305054)
			(end -0.12065 -0.2794)
			(stroke
				(width 0.1)
				(type default)
			)
			(layer "F.Fab")
		)
		(fp_line
			(start -0.67945 -0.305054)
			(end -0.12065 -0.305054)
			(stroke
				(width 0.1)
				(type default)
			)
			(layer "F.Fab")
		)
		(fp_line
			(start 0.67945 -0.3048)
			(end 0.67945 0.3048)
			(stroke
				(width 0.1)
				(type default)
			)
			(layer "F.Fab")
		)
		(fp_line
			(start 0.12065 -0.3048)
			(end 0.67945 -0.3048)
			(stroke
				(width 0.1)
				(type default)
			)
			(layer "F.Fab")
		)
		(fp_line
			(start 0.12065 -0.2794)
			(end 0.12065 -0.3048)
			(stroke
				(width 0.1)
				(type default)
			)
			(layer "F.Fab")
		)
		(fp_line
			(start -0.12065 -0.2794)
			(end 0.12065 -0.2794)
			(stroke
				(width 0.1)
				(type default)
			)
			(layer "F.Fab")
		)
		(fp_line
			(start 0.120396 0.2794)
			(end -0.12065 0.2794)
			(stroke
				(width 0.1)
				(type default)
			)
			(layer "F.Fab")
		)
		(fp_line
			(start -0.12065 0.2794)
			(end -0.12065 0.3048)
			(stroke
				(width 0.1)
				(type default)
			)
			(layer "F.Fab")
		)
		(fp_line
			(start 0.67945 0.3048)
			(end 0.120396 0.3048)
			(stroke
				(width 0.1)
				(type default)
			)
			(layer "F.Fab")
		)
		(fp_line
			(start 0.120396 0.3048)
			(end 0.120396 0.2794)
			(stroke
				(width 0.1)
				(type default)
			)
			(layer "F.Fab")
		)
		(fp_line
			(start -0.12065 0.3048)
			(end -0.67945 0.3048)
			(stroke
				(width 0.1)
				(type default)
			)
			(layer "F.Fab")
		)
		(fp_line
			(start -0.67945 0.3048)
			(end -0.67945 -0.305054)
			(stroke
				(width 0.1)
				(type default)
			)
			(layer "F.Fab")
		)
		(pad "1" smd circle
			(at -0.40005 0 90)
			(size 0 0)
			(layers "F.Cu" "F.Mask" "F.Paste")
			(net "P3V3_AUX")
		)
		(pad "2" smd circle
			(at 0.40005 0 90)
			(size 0 0)
			(layers "F.Cu" "F.Mask" "F.Paste")
			(net "P3V3_PWRGD_CLKGEN")
		)
	)
	(footprint ""
		(layer "F.Cu")
		(at 64.708024 -40.208708 90)
		(property "Reference" "R4067"
			(at 0 0 90)
			(layer "F.SilkS")
			(hide yes)
			(effects
				(font
					(size 1.27 1.27)
				)
			)
		)
		(property "Value" ""
			(at 0 0 90)
			(layer "F.Fab")
			(effects
				(font
					(size 1.27 1.27)
				)
			)
		)
		(duplicate_pad_numbers_are_jumpers no)
		(fp_line
			(start 0.7874 -0.4064)
			(end 0.7874 0.4064)
			(stroke
				(width 0.1524)
				(type default)
			)
			(layer "F.SilkS")
		)
		(fp_line
			(start -0.7874 -0.4064)
			(end 0.7874 -0.4064)
			(stroke
				(width 0.1524)
				(type default)
			)
			(layer "F.SilkS")
		)
		(fp_line
			(start 0.7874 0.4064)
			(end -0.7874 0.4064)
			(stroke
				(width 0.1524)
				(type default)
			)
			(layer "F.SilkS")
		)
		(fp_line
			(start -0.7874 0.4064)
			(end -0.7874 -0.4064)
			(stroke
				(width 0.1524)
				(type default)
			)
			(layer "F.SilkS")
		)
		(fp_line
			(start -0.12065 -0.305054)
			(end -0.12065 -0.2794)
			(stroke
				(width 0.1)
				(type default)
			)
			(layer "F.Fab")
		)
		(fp_line
			(start -0.67945 -0.305054)
			(end -0.12065 -0.305054)
			(stroke
				(width 0.1)
				(type default)
			)
			(layer "F.Fab")
		)
		(fp_line
			(start 0.67945 -0.3048)
			(end 0.67945 0.3048)
			(stroke
				(width 0.1)
				(type default)
			)
			(layer "F.Fab")
		)
		(fp_line
			(start 0.12065 -0.3048)
			(end 0.67945 -0.3048)
			(stroke
				(width 0.1)
				(type default)
			)
			(layer "F.Fab")
		)
		(fp_line
			(start 0.12065 -0.2794)
			(end 0.12065 -0.3048)
			(stroke
				(width 0.1)
				(type default)
			)
			(layer "F.Fab")
		)
		(fp_line
			(start -0.12065 -0.2794)
			(end 0.12065 -0.2794)
			(stroke
				(width 0.1)
				(type default)
			)
			(layer "F.Fab")
		)
		(fp_line
			(start 0.120396 0.2794)
			(end -0.12065 0.2794)
			(stroke
				(width 0.1)
				(type default)
			)
			(layer "F.Fab")
		)
		(fp_line
			(start -0.12065 0.2794)
			(end -0.12065 0.3048)
			(stroke
				(width 0.1)
				(type default)
			)
			(layer "F.Fab")
		)
		(fp_line
			(start 0.67945 0.3048)
			(end 0.120396 0.3048)
			(stroke
				(width 0.1)
				(type default)
			)
			(layer "F.Fab")
		)
		(fp_line
			(start 0.120396 0.3048)
			(end 0.120396 0.2794)
			(stroke
				(width 0.1)
				(type default)
			)
			(layer "F.Fab")
		)
		(fp_line
			(start -0.12065 0.3048)
			(end -0.67945 0.3048)
			(stroke
				(width 0.1)
				(type default)
			)
			(layer "F.Fab")
		)
		(fp_line
			(start -0.67945 0.3048)
			(end -0.67945 -0.305054)
			(stroke
				(width 0.1)
				(type default)
			)
			(layer "F.Fab")
		)
		(pad "1" smd circle
			(at -0.40005 0 90)
			(size 0 0)
			(layers "F.Cu" "F.Mask" "F.Paste")
			(net "P12V_AUX")
		)
		(pad "2" smd circle
			(at 0.40005 0 90)
			(size 0 0)
			(layers "F.Cu" "F.Mask" "F.Paste")
			(net "P3V3_OCP_2_EN_G")
		)
	)
	(footprint ""
		(layer "F.Cu")
		(at 137.176256 -64.694308)
		(property "Reference" "Q46"
			(at -0.3937 2.62763 0)
			(unlocked yes)
			(layer "F.SilkS")
			(effects
				(font
					(size 0.7874 0.5842)
					(thickness 0.1524)
				)
				(justify left)
			)
		)
		(property "Value" ""
			(at 0 0 0)
			(layer "F.Fab")
			(effects
				(font
					(size 1.27 1.27)
				)
			)
		)
		(duplicate_pad_numbers_are_jumpers no)
		(fp_line
			(start -1.603248 -1.500124)
			(end 1.603248 -1.500124)
			(stroke
				(width 0.1524)
				(type default)
			)
			(layer "F.SilkS")
		)
		(fp_line
			(start -1.603248 1.500124)
			(end -1.603248 -1.500124)
			(stroke
				(width 0.1524)
				(type default)
			)
			(layer "F.SilkS")
		)
		(fp_line
			(start 1.603248 -1.500124)
			(end 1.603248 1.500124)
			(stroke
				(width 0.1524)
				(type default)
			)
			(layer "F.SilkS")
		)
		(fp_line
			(start 1.603248 1.500124)
			(end -1.603248 1.500124)
			(stroke
				(width 0.1524)
				(type default)
			)
			(layer "F.SilkS")
		)
		(fp_line
			(start -1.249934 -1.169924)
			(end -1.249934 -0.729996)
			(stroke
				(width 0.1)
				(type default)
			)
			(layer "F.Fab")
		)
		(fp_line
			(start -1.249934 -0.729996)
			(end -0.6985 -0.729996)
			(stroke
				(width 0.1)
				(type default)
			)
			(layer "F.Fab")
		)
		(fp_line
			(start -1.249934 0.729996)
			(end -1.249934 1.169924)
			(stroke
				(width 0.1)
				(type default)
			)
			(layer "F.Fab")
		)
		(fp_line
			(start -1.249934 1.169924)
			(end -0.700024 1.169924)
			(stroke
				(width 0.1)
				(type default)
			)
			(layer "F.Fab")
		)
		(fp_line
			(start -0.700024 -1.500124)
			(end -0.700024 -1.169924)
			(stroke
				(width 0.1)
				(type default)
			)
			(layer "F.Fab")
		)
		(fp_line
			(start -0.700024 -1.169924)
			(end -1.249934 -1.169924)
			(stroke
				(width 0.1)
				(type default)
			)
			(layer "F.Fab")
		)
		(fp_line
			(start -0.700024 1.169924)
			(end -0.700024 1.500124)
			(stroke
				(width 0.1)
				(type default)
			)
			(layer "F.Fab")
		)
		(fp_line
			(start -0.700024 1.500124)
			(end 0.700024 1.500124)
			(stroke
				(width 0.1)
				(type default)
			)
			(layer "F.Fab")
		)
		(fp_line
			(start -0.6985 -0.729996)
			(end -0.6985 0.729996)
			(stroke
				(width 0.1)
				(type default)
			)
			(layer "F.Fab")
		)
		(fp_line
			(start -0.6985 0.729996)
			(end -1.249934 0.729996)
			(stroke
				(width 0.1)
				(type default)
			)
			(layer "F.Fab")
		)
		(fp_line
			(start 0.700024 -1.500124)
			(end -0.700024 -1.500124)
			(stroke
				(width 0.1)
				(type default)
			)
			(layer "F.Fab")
		)
		(fp_line
			(start 0.700024 -0.219964)
			(end 0.700024 -1.500124)
			(stroke
				(width 0.1)
				(type default)
			)
			(layer "F.Fab")
		)
		(fp_line
			(start 0.700024 0.219964)
			(end 1.249934 0.219964)
			(stroke
				(width 0.1)
				(type default)
			)
			(layer "F.Fab")
		)
		(fp_line
			(start 0.700024 1.500124)
			(end 0.700024 0.219964)
			(stroke
				(width 0.1)
				(type default)
			)
			(layer "F.Fab")
		)
		(fp_line
			(start 1.249934 -0.219964)
			(end 0.700024 -0.219964)
			(stroke
				(width 0.1)
				(type default)
			)
			(layer "F.Fab")
		)
		(fp_line
			(start 1.249934 0.219964)
			(end 1.249934 -0.219964)
			(stroke
				(width 0.1)
				(type default)
			)
			(layer "F.Fab")
		)
		(fp_rect
			(start -0.700024 1.500124)
			(end 0.700024 -1.500124)
			(stroke
				(width 0)
				(type default)
			)
			(fill no)
			(layer "F.Fab")
		)
		(pad "D" smd rect
			(at 0.999998 0 270)
			(size 0.8128 0.9144)
			(layers "F.Cu" "F.Mask" "F.Paste")
			(net "E1S_0_PRSNT")
		)
		(pad "G" smd rect
			(at -0.999998 -0.94996 270)
			(size 0.8128 0.9144)
			(layers "F.Cu" "F.Mask" "F.Paste")
			(net "E1S_0_PRSNT_N")
		)
		(pad "S" smd rect
			(at -0.999998 0.94996 270)
			(size 0.8128 0.9144)
			(layers "F.Cu" "F.Mask" "F.Paste")
			(net "GND")
		)
	)
	(footprint ""
		(layer "F.Cu")
		(at 460.1845 -45.693838)
		(property "Reference" "R1824"
			(at 0 0 0)
			(layer "F.SilkS")
			(hide yes)
			(effects
				(font
					(size 1.27 1.27)
				)
			)
		)
		(property "Value" ""
			(at 0 0 0)
			(layer "F.Fab")
			(effects
				(font
					(size 1.27 1.27)
				)
			)
		)
		(duplicate_pad_numbers_are_jumpers no)
		(fp_line
			(start -0.7874 -0.4064)
			(end 0.7874 -0.4064)
			(stroke
				(width 0.1524)
				(type default)
			)
			(layer "F.SilkS")
		)
		(fp_line
			(start -0.7874 0.4064)
			(end -0.7874 -0.4064)
			(stroke
				(width 0.1524)
				(type default)
			)
			(layer "F.SilkS")
		)
		(fp_line
			(start 0.7874 -0.4064)
			(end 0.7874 0.4064)
			(stroke
				(width 0.1524)
				(type default)
			)
			(layer "F.SilkS")
		)
		(fp_line
			(start 0.7874 0.4064)
			(end -0.7874 0.4064)
			(stroke
				(width 0.1524)
				(type default)
			)
			(layer "F.SilkS")
		)
		(fp_line
			(start -0.67945 -0.305054)
			(end -0.12065 -0.305054)
			(stroke
				(width 0.1)
				(type default)
			)
			(layer "F.Fab")
		)
		(fp_line
			(start -0.67945 0.3048)
			(end -0.67945 -0.305054)
			(stroke
				(width 0.1)
				(type default)
			)
			(layer "F.Fab")
		)
		(fp_line
			(start -0.12065 -0.305054)
			(end -0.12065 -0.2794)
			(stroke
				(width 0.1)
				(type default)
			)
			(layer "F.Fab")
		)
		(fp_line
			(start -0.12065 -0.2794)
			(end 0.12065 -0.2794)
			(stroke
				(width 0.1)
				(type default)
			)
			(layer "F.Fab")
		)
		(fp_line
			(start -0.12065 0.2794)
			(end -0.12065 0.3048)
			(stroke
				(width 0.1)
				(type default)
			)
			(layer "F.Fab")
		)
		(fp_line
			(start -0.12065 0.3048)
			(end -0.67945 0.3048)
			(stroke
				(width 0.1)
				(type default)
			)
			(layer "F.Fab")
		)
		(fp_line
			(start 0.120396 0.2794)
			(end -0.12065 0.2794)
			(stroke
				(width 0.1)
				(type default)
			)
			(layer "F.Fab")
		)
		(fp_line
			(start 0.120396 0.3048)
			(end 0.120396 0.2794)
			(stroke
				(width 0.1)
				(type default)
			)
			(layer "F.Fab")
		)
		(fp_line
			(start 0.12065 -0.3048)
			(end 0.67945 -0.3048)
			(stroke
				(width 0.1)
				(type default)
			)
			(layer "F.Fab")
		)
		(fp_line
			(start 0.12065 -0.2794)
			(end 0.12065 -0.3048)
			(stroke
				(width 0.1)
				(type default)
			)
			(layer "F.Fab")
		)
		(fp_line
			(start 0.67945 -0.3048)
			(end 0.67945 0.3048)
			(stroke
				(width 0.1)
				(type default)
			)
			(layer "F.Fab")
		)
		(fp_line
			(start 0.67945 0.3048)
			(end 0.120396 0.3048)
			(stroke
				(width 0.1)
				(type default)
			)
			(layer "F.Fab")
		)
		(pad "1" smd circle
			(at -0.40005 0)
			(size 0 0)
			(layers "F.Cu" "F.Mask" "F.Paste")
			(net "P3V3_OCP_SFF")
		)
		(pad "2" smd circle
			(at 0.40005 0)
			(size 0 0)
			(layers "F.Cu" "F.Mask" "F.Paste")
			(net "IRQ_LVC3_OCP_SFF_WAKE_N")
		)
	)
	(footprint ""
		(layer "F.Cu")
		(at 354.251514 -256.654046 -90)
		(property "Reference" "C974"
			(at 0 0 270)
			(layer "F.SilkS")
			(hide yes)
			(effects
				(font
					(size 1.27 1.27)
				)
			)
		)
		(property "Value" ""
			(at 0 0 270)
			(layer "F.Fab")
			(effects
				(font
					(size 1.27 1.27)
				)
			)
		)
		(duplicate_pad_numbers_are_jumpers no)
		(fp_line
			(start -0.7874 0.4064)
			(end -0.7874 -0.4064)
			(stroke
				(width 0.1524)
				(type default)
			)
			(layer "F.SilkS")
		)
		(fp_line
			(start 0.7874 0.4064)
			(end -0.7874 0.4064)
			(stroke
				(width 0.1524)
				(type default)
			)
			(layer "F.SilkS")
		)
		(fp_line
			(start -0.7874 -0.4064)
			(end 0.7874 -0.4064)
			(stroke
				(width 0.1524)
				(type default)
			)
			(layer "F.SilkS")
		)
		(fp_line
			(start 0.7874 -0.4064)
			(end 0.7874 0.4064)
			(stroke
				(width 0.1524)
				(type default)
			)
			(layer "F.SilkS")
		)
		(fp_line
			(start -0.67945 0.3048)
			(end -0.67945 -0.305054)
			(stroke
				(width 0.1)
				(type default)
			)
			(layer "F.Fab")
		)
		(fp_line
			(start -0.12065 0.3048)
			(end -0.67945 0.3048)
			(stroke
				(width 0.1)
				(type default)
			)
			(layer "F.Fab")
		)
		(fp_line
			(start 0.120396 0.3048)
			(end 0.120396 0.2794)
			(stroke
				(width 0.1)
				(type default)
			)
			(layer "F.Fab")
		)
		(fp_line
			(start 0.67945 0.3048)
			(end 0.120396 0.3048)
			(stroke
				(width 0.1)
				(type default)
			)
			(layer "F.Fab")
		)
		(fp_line
			(start -0.12065 0.2794)
			(end -0.12065 0.3048)
			(stroke
				(width 0.1)
				(type default)
			)
			(layer "F.Fab")
		)
		(fp_line
			(start 0.120396 0.2794)
			(end -0.12065 0.2794)
			(stroke
				(width 0.1)
				(type default)
			)
			(layer "F.Fab")
		)
		(fp_line
			(start -0.12065 -0.2794)
			(end 0.12065 -0.2794)
			(stroke
				(width 0.1)
				(type default)
			)
			(layer "F.Fab")
		)
		(fp_line
			(start 0.12065 -0.2794)
			(end 0.12065 -0.3048)
			(stroke
				(width 0.1)
				(type default)
			)
			(layer "F.Fab")
		)
		(fp_line
			(start 0.12065 -0.3048)
			(end 0.67945 -0.3048)
			(stroke
				(width 0.1)
				(type default)
			)
			(layer "F.Fab")
		)
		(fp_line
			(start 0.67945 -0.3048)
			(end 0.67945 0.3048)
			(stroke
				(width 0.1)
				(type default)
			)
			(layer "F.Fab")
		)
		(fp_line
			(start -0.67945 -0.305054)
			(end -0.12065 -0.305054)
			(stroke
				(width 0.1)
				(type default)
			)
			(layer "F.Fab")
		)
		(fp_line
			(start -0.12065 -0.305054)
			(end -0.12065 -0.2794)
			(stroke
				(width 0.1)
				(type default)
			)
			(layer "F.Fab")
		)
		(pad "1" smd circle
			(at -0.40005 0 270)
			(size 0 0)
			(layers "F.Cu" "F.Mask" "F.Paste")
			(net "PVCCIN_CPU0")
		)
		(pad "2" smd circle
			(at 0.40005 0 270)
			(size 0 0)
			(layers "F.Cu" "F.Mask" "F.Paste")
			(net "GND")
		)
	)
)
